FILE_TYPE=LIBRARY_PARTS;
primitive 'OSC_C','OSC_C_SM';
  pin
    'OUT':
      PIN_NUMBER='(3)';
      PINUSE='UNSPEC';
      NO_LOAD_CHECK='BOTH';
      UNKNOWN_LOADING='TRUE';
      NO_IO_CHECK='BOTH';
      ALLOW_CONNECT='TRUE';
    'IN':
      PIN_NUMBER='(1)';
      PINUSE='UNSPEC';
      NO_LOAD_CHECK='BOTH';
      UNKNOWN_LOADING='TRUE';
      NO_IO_CHECK='BOTH';
      ALLOW_CONNECT='TRUE';
  end_pin;
  body
    PART_NAME='OSC_C';
    PHYS_DES_PREFIX='Y';
    POWER_PINS='(VDD:4)';
    POWER_PINS='(GND:2)';
  end_body;
end_primitive;

primitive 'OSC_C_ALL';
  pin
    'OUT':
      PIN_NUMBER='(3)';
      PINUSE='UNSPEC';
      NO_LOAD_CHECK='BOTH';
      UNKNOWN_LOADING='TRUE';
      NO_IO_CHECK='BOTH';
      ALLOW_CONNECT='TRUE';
    'IN':
      PIN_NUMBER='(1)';
      PINUSE='UNSPEC';
      NO_LOAD_CHECK='BOTH';
      UNKNOWN_LOADING='TRUE';
      NO_IO_CHECK='BOTH';
      ALLOW_CONNECT='TRUE';
    'GND':
      PIN_NUMBER='(2)';
      PINUSE='UNSPEC';
      NO_LOAD_CHECK='BOTH';
      UNKNOWN_LOADING='TRUE';
      NO_IO_CHECK='BOTH';
      ALLOW_CONNECT='TRUE';
    'VDD':
      PIN_NUMBER='(4)';
      PINUSE='UNSPEC';
      NO_LOAD_CHECK='BOTH';
      UNKNOWN_LOADING='TRUE';
      NO_IO_CHECK='BOTH';
      ALLOW_CONNECT='TRUE';
  end_pin;
  body
    PART_NAME='OSC_C';
    PHYS_DES_PREFIX='Y';
  end_body;
end_primitive;

primitive 'OSC_C_6P';
  pin
    'Q':
      PIN_NUMBER='(4)';
      PINUSE='UNSPEC';
      NO_LOAD_CHECK='BOTH';
      UNKNOWN_LOADING='TRUE';
      NO_IO_CHECK='BOTH';
      ALLOW_CONNECT='TRUE';
    'OE1':
      PIN_NUMBER='(1)';
      PINUSE='UNSPEC';
      NO_LOAD_CHECK='BOTH';
      UNKNOWN_LOADING='TRUE';
      NO_IO_CHECK='BOTH';
      ALLOW_CONNECT='TRUE';
    'OE2':
      PIN_NUMBER='(2)';
      PINUSE='UNSPEC';
      NO_LOAD_CHECK='BOTH';
      UNKNOWN_LOADING='TRUE';
      NO_IO_CHECK='BOTH';
      ALLOW_CONNECT='TRUE';
    'VCC':
      PIN_NUMBER='(6)';
      PINUSE='UNSPEC';
      NO_LOAD_CHECK='BOTH';
      UNKNOWN_LOADING='TRUE';
      NO_IO_CHECK='BOTH';
      ALLOW_CONNECT='TRUE';
    'Q_N':
      PIN_NUMBER='(5)';
      PINUSE='UNSPEC';
      NO_LOAD_CHECK='BOTH';
      UNKNOWN_LOADING='TRUE';
      NO_IO_CHECK='BOTH';
      ALLOW_CONNECT='TRUE';
    'VEE':
      PIN_NUMBER='(3)';
      PINUSE='UNSPEC';
      NO_LOAD_CHECK='BOTH';
      UNKNOWN_LOADING='TRUE';
      NO_IO_CHECK='BOTH';
      ALLOW_CONNECT='TRUE';
  end_pin;
  body
    PART_NAME='OSC_C';
    PHYS_DES_PREFIX='Y';
  end_body;
end_primitive;

primitive 'OSC_C_6P2';
  pin
    'OUTPUT1':
      PIN_NUMBER='(4)';
      PINUSE='UNSPEC';
      NO_LOAD_CHECK='BOTH';
      UNKNOWN_LOADING='TRUE';
      NO_IO_CHECK='BOTH';
      ALLOW_CONNECT='TRUE';
    'E_D':
      PIN_NUMBER='(1)';
      PINUSE='UNSPEC';
      NO_LOAD_CHECK='BOTH';
      UNKNOWN_LOADING='TRUE';
      NO_IO_CHECK='BOTH';
      ALLOW_CONNECT='TRUE';
    'NC':
      PIN_NUMBER='(2)';
      PINUSE='UNSPEC';
      NO_LOAD_CHECK='BOTH';
      UNKNOWN_LOADING='TRUE';
      NO_IO_CHECK='BOTH';
      ALLOW_CONNECT='TRUE';
    'VDD':
      PIN_NUMBER='(6)';
      PINUSE='UNSPEC';
      NO_LOAD_CHECK='BOTH';
      UNKNOWN_LOADING='TRUE';
      NO_IO_CHECK='BOTH';
      ALLOW_CONNECT='TRUE';
    'OUTPUT2':
      PIN_NUMBER='(5)';
      PINUSE='UNSPEC';
      NO_LOAD_CHECK='BOTH';
      UNKNOWN_LOADING='TRUE';
      NO_IO_CHECK='BOTH';
      ALLOW_CONNECT='TRUE';
    'GND':
      PIN_NUMBER='(3)';
      PINUSE='UNSPEC';
      NO_LOAD_CHECK='BOTH';
      UNKNOWN_LOADING='TRUE';
      NO_IO_CHECK='BOTH';
      ALLOW_CONNECT='TRUE';
  end_pin;
  body
    PART_NAME='OSC_C';
    PHYS_DES_PREFIX='Y';
  end_body;
end_primitive;

primitive 'OSC_C_6P3';
  pin
    'GND':
      PIN_NUMBER='(3)';
      PINUSE='UNSPEC';
      NO_LOAD_CHECK='BOTH';
      UNKNOWN_LOADING='TRUE';
      NO_IO_CHECK='BOTH';
      ALLOW_CONNECT='TRUE';
    'NC':
      PIN_NUMBER='(5)';
      PINUSE='UNSPEC';
      NO_LOAD_CHECK='BOTH';
      UNKNOWN_LOADING='TRUE';
      NO_IO_CHECK='BOTH';
      ALLOW_CONNECT='TRUE';
    'OUTPUT':
      PIN_NUMBER='(4)';
      PINUSE='UNSPEC';
      NO_LOAD_CHECK='BOTH';
      UNKNOWN_LOADING='TRUE';
      NO_IO_CHECK='BOTH';
      ALLOW_CONNECT='TRUE';
    'O_E_D':
      PIN_NUMBER='(2)';
      PINUSE='UNSPEC';
      NO_LOAD_CHECK='BOTH';
      UNKNOWN_LOADING='TRUE';
      NO_IO_CHECK='BOTH';
      ALLOW_CONNECT='TRUE';
    'VCC':
      PIN_NUMBER='(6)';
      PINUSE='UNSPEC';
      NO_LOAD_CHECK='BOTH';
      UNKNOWN_LOADING='TRUE';
      NO_IO_CHECK='BOTH';
      ALLOW_CONNECT='TRUE';
    'VCI':
      PIN_NUMBER='(1)';
      PINUSE='UNSPEC';
      NO_LOAD_CHECK='BOTH';
      UNKNOWN_LOADING='TRUE';
      NO_IO_CHECK='BOTH';
      ALLOW_CONNECT='TRUE';
  end_pin;
  body
    PART_NAME='OSC_C';
    PHYS_DES_PREFIX='Y';
  end_body;
end_primitive;

primitive 'OSC_C_6P4';
  pin
    'OE':
      PIN_NUMBER='(1)';
      PINUSE='UNSPEC';
      NO_LOAD_CHECK='Both';
      NO_IO_CHECK='Both';
      ALLOW_CONNECT='TRUE';
      UNKNOWN_LOADING='TRUE';
    'NC':
      PIN_NUMBER='(2)';
      PINUSE='UNSPEC';
      NO_LOAD_CHECK='Both';
      NO_IO_CHECK='Both';
      ALLOW_CONNECT='TRUE';
      UNKNOWN_LOADING='TRUE';
    'GND':
      PIN_NUMBER='(3)';
      PINUSE='UNSPEC';
      NO_LOAD_CHECK='Both';
      NO_IO_CHECK='Both';
      ALLOW_CONNECT='TRUE';
      UNKNOWN_LOADING='TRUE';
    'OUT':
      PIN_NUMBER='(4)';
      PINUSE='UNSPEC';
      NO_LOAD_CHECK='Both';
      NO_IO_CHECK='Both';
      ALLOW_CONNECT='TRUE';
      UNKNOWN_LOADING='TRUE';
    'OUT_N':
      PIN_NUMBER='(5)';
      PINUSE='UNSPEC';
      NO_LOAD_CHECK='Both';
      NO_IO_CHECK='Both';
      ALLOW_CONNECT='TRUE';
      UNKNOWN_LOADING='TRUE';
    'VDD':
      PIN_NUMBER='(6)';
      PINUSE='UNSPEC';
      NO_LOAD_CHECK='Both';
      NO_IO_CHECK='Both';
      ALLOW_CONNECT='TRUE';
      UNKNOWN_LOADING='TRUE';
  end_pin;
  body
    PART_NAME='OSC_C';
    PHYS_DES_PREFIX='Y';
  end_body;
end_primitive;

primitive 'OSC_C_6P5';
  pin
    'OE':
      PIN_NUMBER='(1)';
      PINUSE='UNSPEC';
      NO_LOAD_CHECK='Both';
      NO_IO_CHECK='Both';
      ALLOW_CONNECT='TRUE';
      UNKNOWN_LOADING='TRUE';
    'NC':
      PIN_NUMBER='(2)';
      PINUSE='UNSPEC';
      NO_LOAD_CHECK='Both';
      NO_IO_CHECK='Both';
      ALLOW_CONNECT='TRUE';
      UNKNOWN_LOADING='TRUE';
    'GND':
      PIN_NUMBER='(3)';
      PINUSE='UNSPEC';
      NO_LOAD_CHECK='Both';
      NO_IO_CHECK='Both';
      ALLOW_CONNECT='TRUE';
      UNKNOWN_LOADING='TRUE';
    'Q':
      PIN_NUMBER='(4)';
      PINUSE='UNSPEC';
      NO_LOAD_CHECK='Both';
      NO_IO_CHECK='Both';
      ALLOW_CONNECT='TRUE';
      UNKNOWN_LOADING='TRUE';
    'Q_N':
      PIN_NUMBER='(5)';
      PINUSE='UNSPEC';
      NO_LOAD_CHECK='Both';
      NO_IO_CHECK='Both';
      ALLOW_CONNECT='TRUE';
      UNKNOWN_LOADING='TRUE';
    'VCC':
      PIN_NUMBER='(6)';
      PINUSE='UNSPEC';
      NO_LOAD_CHECK='Both';
      NO_IO_CHECK='Both';
      ALLOW_CONNECT='TRUE';
      UNKNOWN_LOADING='TRUE';
  end_pin;
  body
    PART_NAME='OSC_C';
    PHYS_DES_PREFIX='Y';
  end_body;
end_primitive;

primitive 'OSC_C_6P6';
  pin
    'NC':
      PIN_NUMBER='(2)';
      PINUSE='NC';
      NO_LOAD_CHECK='Both';
      NO_IO_CHECK='Both';
      NO_ASSERT_CHECK='TRUE';
      NO_DIR_CHECK='TRUE';
      ALLOW_CONNECT='TRUE';
    'OE':
      PIN_NUMBER='(1)';
      BIDIRECTIONAL='TRUE';
      INPUT_LOAD='(-0.01,0.01)';
      OUTPUT_LOAD='(1.0,-1.0)';
    'VCC':
      PIN_NUMBER='(6)';
      PINUSE='POWER';
      NO_LOAD_CHECK='Both';
      NO_IO_CHECK='Both';
      NO_ASSERT_CHECK='TRUE';
      NO_DIR_CHECK='TRUE';
      ALLOW_CONNECT='TRUE';
    'OUT_N':
      PIN_NUMBER='(5)';
      OUTPUT_LOAD='(1.0,-1.0)';
    'OUT':
      PIN_NUMBER='(4)';
      OUTPUT_LOAD='(1.0,-1.0)';
    'VEE':
      PIN_NUMBER='(3)';
      BIDIRECTIONAL='TRUE';
      INPUT_LOAD='(-0.01,0.01)';
      OUTPUT_LOAD='(1.0,-1.0)';
  end_pin;
  body
    PART_NAME='OSC_C';
    PHYS_DES_PREFIX='Y';
  end_body;
end_primitive;

primitive 'OSC_C_SM2';
  pin
    'GND':
      PIN_NUMBER='(2)';
      PINUSE='GROUND';
      NO_LOAD_CHECK='Both';
      NO_IO_CHECK='Both';
      NO_ASSERT_CHECK='TRUE';
      NO_DIR_CHECK='TRUE';
      ALLOW_CONNECT='TRUE';
    'CLK':
      PIN_NUMBER='(3)';
      OUTPUT_LOAD='(1.0,-1.0)';
    'VDD':
      PIN_NUMBER='(4)';
      PINUSE='POWER';
      NO_LOAD_CHECK='Both';
      NO_IO_CHECK='Both';
      NO_ASSERT_CHECK='TRUE';
      NO_DIR_CHECK='TRUE';
      ALLOW_CONNECT='TRUE';
    'OE_ST_N':
      PIN_NUMBER='(1)';
      INPUT_LOAD='(-0.01,0.01)';
  end_pin;
  body
    PART_NAME='OSC_C';
    PHYS_DES_PREFIX='Y';
  end_body;
end_primitive;

primitive 'OSC_C_SM3';
  pin
    'GND':
      PIN_NUMBER='(2)';
      PINUSE='GROUND';
      NO_LOAD_CHECK='Both';
      NO_IO_CHECK='Both';
      NO_ASSERT_CHECK='TRUE';
      NO_DIR_CHECK='TRUE';
      ALLOW_CONNECT='TRUE';
    'OUTPUT':
      PIN_NUMBER='(3)';
      OUTPUT_LOAD='(1.0,-1.0)';
    'VDD':
      PIN_NUMBER='(4)';
      PINUSE='POWER';
      NO_LOAD_CHECK='Both';
      NO_IO_CHECK='Both';
      NO_ASSERT_CHECK='TRUE';
      NO_DIR_CHECK='TRUE';
      ALLOW_CONNECT='TRUE';
    'STANDBY_N':
      PIN_NUMBER='(1)';
      INPUT_LOAD='(-0.01,0.01)';
  end_pin;
  body
    PART_NAME='OSC_C';
    PHYS_DES_PREFIX='Y';
  end_body;
end_primitive;

primitive 'OSC_C_SM4';
  pin
    'ENABLE_CONTROL':
      PIN_NUMBER='(1)';
      INPUT_LOAD='(-0.01,0.01)';
    'GND':
      PIN_NUMBER='(2)';
      PINUSE='GROUND';
      NO_LOAD_CHECK='Both';
      NO_IO_CHECK='Both';
      NO_ASSERT_CHECK='TRUE';
      NO_DIR_CHECK='TRUE';
      ALLOW_CONNECT='TRUE';
    'OUT':
      PIN_NUMBER='(3)';
      OUTPUT_LOAD='(1.0,-1.0)';
    'VDD':
      PIN_NUMBER='(4)';
      PINUSE='POWER';
      NO_LOAD_CHECK='Both';
      NO_IO_CHECK='Both';
      NO_ASSERT_CHECK='TRUE';
      NO_DIR_CHECK='TRUE';
      ALLOW_CONNECT='TRUE';
  end_pin;
  body
    PART_NAME='OSC_C';
    PHYS_DES_PREFIX='Y';
  end_body;
end_primitive;

primitive 'OSC_C_6P7';
  pin
    'OE':
      PIN_NUMBER='(1)';
      INPUT_LOAD='(-0.01,0.01)';
    'FSEL':
      PIN_NUMBER='(2)';
      INPUT_LOAD='(-0.01,0.01)';
    'VDD':
      PIN_NUMBER='(6)';
      PINUSE='POWER';
      NO_LOAD_CHECK='Both';
      NO_IO_CHECK='Both';
      NO_ASSERT_CHECK='TRUE';
      NO_DIR_CHECK='TRUE';
      ALLOW_CONNECT='TRUE';
    'CLK_N':
      PIN_NUMBER='(5)';
      OUTPUT_LOAD='(1.0,-1.0)';
    'CLK':
      PIN_NUMBER='(4)';
      OUTPUT_LOAD='(1.0,-1.0)';
    'GND':
      PIN_NUMBER='(3)';
      PINUSE='GROUND';
      NO_LOAD_CHECK='Both';
      NO_IO_CHECK='Both';
      NO_ASSERT_CHECK='TRUE';
      NO_DIR_CHECK='TRUE';
      ALLOW_CONNECT='TRUE';
  end_pin;
  body
    PART_NAME='OSC_C';
    PHYS_DES_PREFIX='Y';
  end_body;
end_primitive;

primitive 'OSC_C_SM5';
  pin
    'OE':
      PIN_NUMBER='(1)';
      INPUT_LOAD='(-0.01,0.01)';
    'GND':
      PIN_NUMBER='(2)';
      PINUSE='GROUND';
      NO_LOAD_CHECK='Both';
      NO_IO_CHECK='Both';
      NO_ASSERT_CHECK='TRUE';
      NO_DIR_CHECK='TRUE';
      ALLOW_CONNECT='TRUE';
    'CLK':
      PIN_NUMBER='(3)';
      OUTPUT_LOAD='(1.0,-1.0)';
    'VDD':
      PIN_NUMBER='(4)';
      PINUSE='POWER';
      NO_LOAD_CHECK='Both';
      NO_IO_CHECK='Both';
      NO_ASSERT_CHECK='TRUE';
      NO_DIR_CHECK='TRUE';
      ALLOW_CONNECT='TRUE';
  end_pin;
  body
    PART_NAME='OSC_C';
    PHYS_DES_PREFIX='Y';
  end_body;
end_primitive;

primitive 'OSC_C_SM6';
  pin
    'VOLT_CNTRL':
      PIN_NUMBER='(1)';
      INPUT_LOAD='(-0.01,0.01)';
    'GND':
      PIN_NUMBER='(2)';
      PINUSE='GROUND';
      NO_LOAD_CHECK='Both';
      NO_IO_CHECK='Both';
      NO_ASSERT_CHECK='TRUE';
      NO_DIR_CHECK='TRUE';
      ALLOW_CONNECT='TRUE';
    'OUT':
      PIN_NUMBER='(3)';
      OUTPUT_LOAD='(1.0,-1.0)';
    'VDD':
      PIN_NUMBER='(4)';
      PINUSE='POWER';
      NO_LOAD_CHECK='Both';
      NO_IO_CHECK='Both';
      NO_ASSERT_CHECK='TRUE';
      NO_DIR_CHECK='TRUE';
      ALLOW_CONNECT='TRUE';
  end_pin;
  body
    PART_NAME='OSC_C';
    PHYS_DES_PREFIX='Y';
  end_body;
end_primitive;

primitive 'OSC_C_SM7';
  pin
    'E_D':
      PIN_NUMBER='(1)';
      INPUT_LOAD='(-0.01,0.01)';
    'GND':
      PIN_NUMBER='(2)';
      PINUSE='GROUND';
      NO_LOAD_CHECK='Both';
      NO_IO_CHECK='Both';
      NO_ASSERT_CHECK='TRUE';
      NO_DIR_CHECK='TRUE';
      ALLOW_CONNECT='TRUE';
    'OUTPUT':
      PIN_NUMBER='(3)';
      OUTPUT_LOAD='(1.0,-1.0)';
    'VDD':
      PIN_NUMBER='(4)';
      PINUSE='POWER';
      NO_LOAD_CHECK='Both';
      NO_IO_CHECK='Both';
      NO_ASSERT_CHECK='TRUE';
      NO_DIR_CHECK='TRUE';
      ALLOW_CONNECT='TRUE';
  end_pin;
  body
    PART_NAME='OSC_C';
    BODY_NAME='OSC_C';
    PHYS_DES_PREFIX='Y';
  end_body;
end_primitive;

primitive 'OSC_C_6P8';
  pin
    'NC':
      PIN_NUMBER='(1)';
      PINUSE='NC';
      NO_LOAD_CHECK='Both';
      NO_IO_CHECK='Both';
      NO_ASSERT_CHECK='TRUE';
      NO_DIR_CHECK='TRUE';
      ALLOW_CONNECT='TRUE';
    'OE':
      PIN_NUMBER='(2)';
      INPUT_LOAD='(-0.01,0.01)';
    'VDD':
      PIN_NUMBER='(6)';
      PINUSE='POWER';
      NO_LOAD_CHECK='Both';
      NO_IO_CHECK='Both';
      NO_ASSERT_CHECK='TRUE';
      NO_DIR_CHECK='TRUE';
      ALLOW_CONNECT='TRUE';
    'CLKM':
      PIN_NUMBER='(5)';
      OUTPUT_LOAD='(1.0,-1.0)';
    'CLKP':
      PIN_NUMBER='(4)';
      OUTPUT_LOAD='(1.0,-1.0)';
    'GND':
      PIN_NUMBER='(3)';
      PINUSE='GROUND';
      NO_LOAD_CHECK='Both';
      NO_IO_CHECK='Both';
      NO_ASSERT_CHECK='TRUE';
      NO_DIR_CHECK='TRUE';
      ALLOW_CONNECT='TRUE';
  end_pin;
  body
    PART_NAME='OSC_C';
    PHYS_DES_PREFIX='Y';
  end_body;
end_primitive;

primitive 'OSC_C_6P9';
  pin
    'VCC':
      PIN_NUMBER='(6)';
      PINUSE='POWER';
      NO_LOAD_CHECK='Both';
      NO_IO_CHECK='Both';
      NO_ASSERT_CHECK='TRUE';
      NO_DIR_CHECK='TRUE';
      ALLOW_CONNECT='TRUE';
    'GND':
      PIN_NUMBER='(3)';
      PINUSE='GROUND';
      NO_LOAD_CHECK='Both';
      NO_IO_CHECK='Both';
      NO_ASSERT_CHECK='TRUE';
      NO_DIR_CHECK='TRUE';
      ALLOW_CONNECT='TRUE';
    'Q_OUT_N':
      PIN_NUMBER='(5)';
      OUTPUT_LOAD='(1.0,-1.0)';
    'Q_OUT':
      PIN_NUMBER='(4)';
      OUTPUT_LOAD='(1.0,-1.0)';
    'OE_NC':
      PIN_NUMBER='(1)';
      BIDIRECTIONAL='TRUE';
      INPUT_LOAD='(-0.01,0.01)';
      OUTPUT_LOAD='(1.0,-1.0)';
    'NC_OE':
      PIN_NUMBER='(2)';
      BIDIRECTIONAL='TRUE';
      INPUT_LOAD='(-0.01,0.01)';
      OUTPUT_LOAD='(1.0,-1.0)';
  end_pin;
  body
    PART_NAME='OSC_C';
    PHYS_DES_PREFIX='Y';
  end_body;
end_primitive;
primitive 'OSC_C_6P10';
  pin
    'ENABLE_DISABLE':
      PIN_NUMBER='(1)';
      BIDIRECTIONAL='TRUE';
      INPUT_LOAD='(-0.01,0.01)';
      OUTPUT_LOAD='(1.0,-1.0)';
    'NC_GND':
      PIN_NUMBER='(2)';
      PINUSE='NC';
      NO_LOAD_CHECK='Both';
      NO_IO_CHECK='Both';
      NO_ASSERT_CHECK='TRUE';
      NO_DIR_CHECK='TRUE';
      ALLOW_CONNECT='TRUE';
    'GND':
      PIN_NUMBER='(3)';
      PINUSE='GROUND';
      NO_LOAD_CHECK='Both';
      NO_IO_CHECK='Both';
      NO_ASSERT_CHECK='TRUE';
      NO_DIR_CHECK='TRUE';
      ALLOW_CONNECT='TRUE';
    'OUT':
      PIN_NUMBER='(4)';
      OUTPUT_LOAD='(1.0,-1.0)';
    'OUT_N':
      PIN_NUMBER='(5)';
      OUTPUT_LOAD='(1.0,-1.0)';
    'VCC':
      PIN_NUMBER='(6)';
      PINUSE='POWER';
      NO_LOAD_CHECK='Both';
      NO_IO_CHECK='Both';
      NO_ASSERT_CHECK='TRUE';
      NO_DIR_CHECK='TRUE';
      ALLOW_CONNECT='TRUE';
  end_pin;
  body
    PART_NAME='OSC_C';
    PHYS_DES_PREFIX='Y';
  end_body;
end_primitive;
primitive 'OSC_C_6P11';
  pin
    'NC':
      PIN_NUMBER='(2)';
      PINUSE='NC';
      NO_LOAD_CHECK='Both';
      NO_IO_CHECK='Both';
      NO_ASSERT_CHECK='TRUE';
      NO_DIR_CHECK='TRUE';
      ALLOW_CONNECT='TRUE';
    'OE':
      PIN_NUMBER='(1)';
      BIDIRECTIONAL='TRUE';
      INPUT_LOAD='(-0.01,0.01)';
      OUTPUT_LOAD='(1.0,-1.0)';
    'VCC':
      PIN_NUMBER='(6)';
      PINUSE='POWER';
      NO_LOAD_CHECK='Both';
      NO_IO_CHECK='Both';
      NO_ASSERT_CHECK='TRUE';
      NO_DIR_CHECK='TRUE';
      ALLOW_CONNECT='TRUE';
    'OUT_N':
      PIN_NUMBER='(5)';
      OUTPUT_LOAD='(1.0,-1.0)';
    'OUT':
      PIN_NUMBER='(4)';
      OUTPUT_LOAD='(1.0,-1.0)';
    'GND':
      PIN_NUMBER='(3)';
      PINUSE='GROUND';
      NO_LOAD_CHECK='Both';
      NO_IO_CHECK='Both';
      NO_ASSERT_CHECK='TRUE';
      NO_DIR_CHECK='TRUE';
      ALLOW_CONNECT='TRUE';
  end_pin;
  body
    PART_NAME='OSC_C';
    PHYS_DES_PREFIX='Y';
  end_body;
end_primitive;
primitive 'OSC_C_6P12';
  pin
    'Q':
      PIN_NUMBER='(4)';
      OUTPUT_LOAD='(1.0,-1.0)';
    'OE':
      PIN_NUMBER='(1)';
      INPUT_LOAD='(-0.01,0.01)';
    'DNC':
      PIN_NUMBER='(2)';
      PINUSE='NC';
      NO_LOAD_CHECK='Both';
      NO_IO_CHECK='Both';
      NO_ASSERT_CHECK='TRUE';
      NO_DIR_CHECK='TRUE';
      ALLOW_CONNECT='TRUE';
    'VDD':
      PIN_NUMBER='(6)';
      PINUSE='POWER';
      NO_LOAD_CHECK='Both';
      NO_IO_CHECK='Both';
      NO_ASSERT_CHECK='TRUE';
      NO_DIR_CHECK='TRUE';
      ALLOW_CONNECT='TRUE';
    'Q_N':
      PIN_NUMBER='(5)';
      OUTPUT_LOAD='(1.0,-1.0)';
    'GND':
      PIN_NUMBER='(3)';
      PINUSE='GROUND';
      NO_LOAD_CHECK='Both';
      NO_IO_CHECK='Both';
      NO_ASSERT_CHECK='TRUE';
      NO_DIR_CHECK='TRUE';
      ALLOW_CONNECT='TRUE';
  end_pin;
  body
    PART_NAME='OSC_C';
    PHYS_DES_PREFIX='Y';
  end_body;
end_primitive;

END.
